FILE_TYPE = CONNECTIVITY;
{Allegro Design Entry HDL 17.4-2019 S026 (4007227) 1/17/2022}
"PAGE_NUMBER" = 390;
0"NC";
END.
